(kicad_pcb
	(version 20260206)
	(generator "pcbnew")
	(generator_version "10.0")
	(general
		(thickness 1.6)
		(legacy_teardrops no)
	)
	(paper "A4")
	(title_block
		(title "baseboard — 13948-1b.1110WZS1818.brd")
		(comment 1 "Honey Badger (Wiwynn) / footprints 1182-1188 of 2523")
	)
	(layers
		(0 "F.Cu" signal "TOP")
		(4 "In1.Cu" signal "L2GND")
		(6 "In2.Cu" signal "L3")
		(8 "In3.Cu" signal "L4VCC")
		(10 "In4.Cu" signal "L5VCC")
		(12 "In5.Cu" signal "L6")
		(14 "In6.Cu" signal "L7GND")
		(2 "B.Cu" signal "BOTTOM")
		(9 "F.Adhes" user "F.Adhesive")
		(11 "B.Adhes" user "B.Adhesive")
		(13 "F.Paste" user "Package Geometry/Pastemask Top")
		(15 "B.Paste" user "Package Geometry/Pastemask Bottom")
		(5 "F.SilkS" user "Ref Des/Silkscreen Top")
		(7 "B.SilkS" user "Ref Des/Silkscreen Bottom")
		(1 "F.Mask" user "Board Geometry/Soldermask Top")
		(3 "B.Mask" user "Board Geometry/Soldermask Bottom")
		(17 "Dwgs.User" user "User.Drawings")
		(19 "Cmts.User" user "User.Comments")
		(21 "Eco1.User" user "User.Eco1")
		(23 "Eco2.User" user "User.Eco2")
		(25 "Edge.Cuts" user "Board Geometry/Outline")
		(27 "Margin" user)
		(31 "F.CrtYd" user "Package Geometry/Place Bound Top")
		(29 "B.CrtYd" user "Package Geometry/Place Bound Bottom")
		(35 "F.Fab" user "Ref Des/Assembly Top")
		(33 "B.Fab" user "Ref Des/Assembly Bottom")
	)
	(footprint ""
		(layer "F.Cu")
		(at 117.456966 -33.909)
		(property "Reference" "STP25"
			(at 0 0 0)
			(layer "F.SilkS")
			(hide yes)
			(effects
				(font
					(size 1.27 1.27)
				)
			)
		)
		(property "Value" "TPAD28"
			(at 0.0127 -1.8034 0)
			(unlocked yes)
			(layer "F.Fab")
			(hide yes)
			(effects
				(font
					(size 1.016 1.016)
					(thickness 0.1524)
				)
			)
		)
		(property "Device Type" "TPAD28"
			(at 0.0127 -3.3274 0)
			(unlocked yes)
			(layer "F.Fab")
			(hide yes)
			(effects
				(font
					(size 1.016 1.016)
					(thickness 0.1524)
				)
			)
		)
		(duplicate_pad_numbers_are_jumpers no)
		(fp_poly
			(pts
				(arc
					(start 0.3556 0)
					(mid -0.3556 0)
					(end 0.3556 0)
				)
			)
			(stroke
				(width 0)
				(type default)
			)
			(fill no)
			(layer "F.CrtYd")
		)
		(fp_poly
			(pts
				(arc
					(start 0.6096 0)
					(mid -0.6096 0)
					(end 0.6096 0)
				)
			)
			(stroke
				(width 0)
				(type default)
			)
			(fill no)
			(layer "F.Fab")
		)
		(pad "1" smd circle
			(at 0 0)
			(size 0.7112 0.7112)
			(layers "F.Cu" "F.Mask" "F.Paste")
			(net "IOC_GPIO_39")
		)
	)
	(footprint ""
		(layer "F.Cu")
		(at 177.537872 -198.369936)
		(property "Reference" "R428"
			(at 0 0 0)
			(layer "F.SilkS")
			(hide yes)
			(effects
				(font
					(size 1.27 1.27)
				)
			)
		)
		(property "Value" "10KR2F-2-GP"
			(at 0.064008 -3.993896 0)
			(unlocked yes)
			(layer "F.Fab")
			(hide yes)
			(effects
				(font
					(size 1.016 1.016)
					(thickness 0.1524)
				)
			)
		)
		(property "Device Type" "R402H16"
			(at 0.064008 -5.517896 0)
			(unlocked yes)
			(layer "F.Fab")
			(hide yes)
			(effects
				(font
					(size 1.016 1.016)
					(thickness 0.1524)
				)
			)
		)
		(duplicate_pad_numbers_are_jumpers no)
		(fp_line
			(start -0.508 -0.9398)
			(end -0.508 0.9398)
			(stroke
				(width 0.1524)
				(type default)
			)
			(layer "F.SilkS")
		)
		(fp_line
			(start 0.508 -0.9398)
			(end -0.508 -0.9398)
			(stroke
				(width 0.1524)
				(type default)
			)
			(layer "F.SilkS")
		)
		(fp_rect
			(start -0.508 0.9398)
			(end 0.508 -0.9398)
			(stroke
				(width 0)
				(type default)
			)
			(fill no)
			(layer "F.CrtYd")
		)
		(fp_rect
			(start -0.508 0.9398)
			(end 0.508 -0.9398)
			(stroke
				(width 0)
				(type default)
			)
			(fill no)
			(layer "F.Fab")
		)
		(pad "1" smd custom
			(at 0 -0.4445)
			(size 0.1397 0.1397)
			(layers "F.Cu" "F.Mask" "F.Paste")
			(net "P3V3_STBY")
			(options
				(clearance outline)
				(anchor circle)
			)
			(primitives
				(gr_poly
					(pts
						(arc
							(start -0.1778 -0.2794)
							(mid -0.249642 -0.249642)
							(end -0.2794 -0.1778)
						)
						(arc
							(start -0.2794 0.1778)
							(mid -0.249642 0.249642)
							(end -0.1778 0.2794)
						)
						(arc
							(start 0.1778 0.2794)
							(mid 0.249642 0.249642)
							(end 0.2794 0.1778)
						)
						(arc
							(start 0.2794 -0.1778)
							(mid 0.249642 -0.249642)
							(end 0.1778 -0.2794)
						)
					)
					(width 0)
					(fill yes)
				)
			)
		)
		(pad "2" smd custom
			(at 0 0.4445)
			(size 0.1397 0.1397)
			(layers "F.Cu" "F.Mask" "F.Paste")
			(net "I2C_C_BUFF_EN")
			(options
				(clearance outline)
				(anchor circle)
			)
			(primitives
				(gr_poly
					(pts
						(arc
							(start -0.1778 -0.2794)
							(mid -0.249642 -0.249642)
							(end -0.2794 -0.1778)
						)
						(arc
							(start -0.2794 0.1778)
							(mid -0.249642 0.249642)
							(end -0.1778 0.2794)
						)
						(arc
							(start 0.1778 0.2794)
							(mid 0.249642 0.249642)
							(end 0.2794 0.1778)
						)
						(arc
							(start 0.2794 -0.1778)
							(mid 0.249642 -0.249642)
							(end 0.1778 -0.2794)
						)
					)
					(width 0)
					(fill yes)
				)
			)
		)
	)
	(footprint ""
		(layer "F.Cu")
		(at 279.2857 -213.03996)
		(property "Reference" "TP181"
			(at 0 0 0)
			(layer "F.SilkS")
			(hide yes)
			(effects
				(font
					(size 1.27 1.27)
				)
			)
		)
		(property "Value" "TPAD28"
			(at -0.0127 -1.6637 0)
			(unlocked yes)
			(layer "F.Fab")
			(hide yes)
			(effects
				(font
					(size 1.016 1.016)
					(thickness 0.1524)
				)
			)
		)
		(property "Device Type" "TPAD28"
			(at -0.0127 -3.1877 0)
			(unlocked yes)
			(layer "F.Fab")
			(hide yes)
			(effects
				(font
					(size 1.016 1.016)
					(thickness 0.1524)
				)
			)
		)
		(duplicate_pad_numbers_are_jumpers no)
		(fp_poly
			(pts
				(arc
					(start 0.3556 0)
					(mid -0.3556 0)
					(end 0.3556 0)
				)
			)
			(stroke
				(width 0)
				(type default)
			)
			(fill no)
			(layer "F.CrtYd")
		)
		(fp_poly
			(pts
				(arc
					(start 0.6096 0)
					(mid -0.6096 0)
					(end 0.6096 0)
				)
			)
			(stroke
				(width 0)
				(type default)
			)
			(fill no)
			(layer "F.Fab")
		)
		(pad "1" smd circle
			(at 0 0)
			(size 0.7112 0.7112)
			(layers "F.Cu" "F.Mask" "F.Paste")
			(net "FM_BMC_RESET_N")
		)
	)
	(footprint ""
		(layer "F.Cu")
		(at 304.918872 -205.177136 -90)
		(property "Reference" "C143"
			(at 0 0 270)
			(layer "F.SilkS")
			(hide yes)
			(effects
				(font
					(size 1.27 1.27)
				)
			)
		)
		(property "Value" "SCD01U50V2KX-1GP"
			(at 1.1811 -2.7051 270)
			(unlocked yes)
			(layer "F.Fab")
			(hide yes)
			(effects
				(font
					(size 1.016 1.016)
					(thickness 0.1524)
				)
			)
		)
		(property "Device Type" "C402H22"
			(at 1.1811 -4.2291 270)
			(unlocked yes)
			(layer "F.Fab")
			(hide yes)
			(effects
				(font
					(size 1.016 1.016)
					(thickness 0.1524)
				)
			)
		)
		(duplicate_pad_numbers_are_jumpers no)
		(fp_rect
			(start -0.4318 0.9525)
			(end 0.4318 -0.9525)
			(stroke
				(width 0)
				(type default)
			)
			(fill no)
			(layer "F.CrtYd")
		)
		(fp_rect
			(start -0.4318 0.9525)
			(end 0.4318 -0.9525)
			(stroke
				(width 0)
				(type default)
			)
			(fill no)
			(layer "F.Fab")
		)
		(pad "1" smd custom
			(at 0 -0.4445 270)
			(size 0.1524 0.1524)
			(layers "F.Cu" "F.Mask" "F.Paste")
			(net "P3V3_STBY")
			(options
				(clearance outline)
				(anchor circle)
			)
			(primitives
				(gr_poly
					(pts
						(arc
							(start 0.3048 -0.2032)
							(mid 0.275042 -0.275042)
							(end 0.2032 -0.3048)
						)
						(arc
							(start -0.2032 -0.3048)
							(mid -0.275042 -0.275042)
							(end -0.3048 -0.2032)
						)
						(arc
							(start -0.3048 0.2032)
							(mid -0.275042 0.275042)
							(end -0.2032 0.3048)
						)
						(arc
							(start 0.2032 0.3048)
							(mid 0.275042 0.275042)
							(end 0.3048 0.2032)
						)
					)
					(width 0)
					(fill yes)
				)
			)
		)
		(pad "2" smd custom
			(at 0 0.4445 270)
			(size 0.1524 0.1524)
			(layers "F.Cu" "F.Mask" "F.Paste")
			(net "GND")
			(options
				(clearance outline)
				(anchor circle)
			)
			(primitives
				(gr_poly
					(pts
						(arc
							(start 0.3048 -0.2032)
							(mid 0.275042 -0.275042)
							(end 0.2032 -0.3048)
						)
						(arc
							(start -0.2032 -0.3048)
							(mid -0.275042 -0.275042)
							(end -0.3048 -0.2032)
						)
						(arc
							(start -0.3048 0.2032)
							(mid -0.275042 0.275042)
							(end -0.2032 0.3048)
						)
						(arc
							(start 0.2032 0.3048)
							(mid 0.275042 0.275042)
							(end 0.3048 0.2032)
						)
					)
					(width 0)
					(fill yes)
				)
			)
		)
	)
	(footprint ""
		(layer "F.Cu")
		(at 173.473872 -194.051936 180)
		(property "Reference" "R427"
			(at 0 0 180)
			(layer "F.SilkS")
			(hide yes)
			(effects
				(font
					(size 1.27 1.27)
				)
			)
		)
		(property "Value" "2KR2F-3-GP"
			(at 0.064008 -3.993896 180)
			(unlocked yes)
			(layer "F.Fab")
			(hide yes)
			(effects
				(font
					(size 1.016 1.016)
					(thickness 0.1524)
				)
			)
		)
		(property "Device Type" "R402H16"
			(at 0.064008 -5.517896 180)
			(unlocked yes)
			(layer "F.Fab")
			(hide yes)
			(effects
				(font
					(size 1.016 1.016)
					(thickness 0.1524)
				)
			)
		)
		(duplicate_pad_numbers_are_jumpers no)
		(fp_line
			(start 0.508 -0.9398)
			(end -0.508 -0.9398)
			(stroke
				(width 0.1524)
				(type default)
			)
			(layer "F.SilkS")
		)
		(fp_line
			(start -0.508 -0.9398)
			(end -0.508 0.9398)
			(stroke
				(width 0.1524)
				(type default)
			)
			(layer "F.SilkS")
		)
		(fp_rect
			(start -0.508 0.9398)
			(end 0.508 -0.9398)
			(stroke
				(width 0)
				(type default)
			)
			(fill no)
			(layer "F.CrtYd")
		)
		(fp_rect
			(start -0.508 0.9398)
			(end 0.508 -0.9398)
			(stroke
				(width 0)
				(type default)
			)
			(fill no)
			(layer "F.Fab")
		)
		(pad "1" smd custom
			(at 0 -0.4445 180)
			(size 0.1397 0.1397)
			(layers "F.Cu" "F.Mask" "F.Paste")
			(net "P3V3_STBY")
			(options
				(clearance outline)
				(anchor circle)
			)
			(primitives
				(gr_poly
					(pts
						(arc
							(start -0.1778 -0.2794)
							(mid -0.249642 -0.249642)
							(end -0.2794 -0.1778)
						)
						(arc
							(start -0.2794 0.1778)
							(mid -0.249642 0.249642)
							(end -0.1778 0.2794)
						)
						(arc
							(start 0.1778 0.2794)
							(mid 0.249642 0.249642)
							(end 0.2794 0.1778)
						)
						(arc
							(start 0.2794 -0.1778)
							(mid 0.249642 -0.249642)
							(end 0.1778 -0.2794)
						)
					)
					(width 0)
					(fill yes)
				)
			)
		)
		(pad "2" smd custom
			(at 0 0.4445 180)
			(size 0.1397 0.1397)
			(layers "F.Cu" "F.Mask" "F.Paste")
			(net "SAS_I2C_C_BUF_SCL")
			(options
				(clearance outline)
				(anchor circle)
			)
			(primitives
				(gr_poly
					(pts
						(arc
							(start -0.1778 -0.2794)
							(mid -0.249642 -0.249642)
							(end -0.2794 -0.1778)
						)
						(arc
							(start -0.2794 0.1778)
							(mid -0.249642 0.249642)
							(end -0.1778 0.2794)
						)
						(arc
							(start 0.1778 0.2794)
							(mid 0.249642 0.249642)
							(end 0.2794 0.1778)
						)
						(arc
							(start 0.2794 -0.1778)
							(mid 0.249642 -0.249642)
							(end 0.1778 -0.2794)
						)
					)
					(width 0)
					(fill yes)
				)
			)
		)
	)
	(footprint ""
		(layer "F.Cu")
		(at 29.922216 -231.57688)
		(property "Reference" "SU13"
			(at 0 0 0)
			(layer "F.SilkS")
			(hide yes)
			(effects
				(font
					(size 1.27 1.27)
				)
			)
		)
		(property "Value" "PI3C3861-AQE-GP"
			(at 0 -13.1572 0)
			(unlocked yes)
			(layer "F.Fab")
			(hide yes)
			(effects
				(font
					(size 1.016 1.016)
					(thickness 0.1524)
				)
			)
		)
		(property "Device Type" "QSOIC24H69"
			(at 0 -15.1892 0)
			(unlocked yes)
			(layer "F.Fab")
			(hide yes)
			(effects
				(font
					(size 1.016 1.016)
					(thickness 0.1524)
				)
			)
		)
		(duplicate_pad_numbers_are_jumpers no)
		(fp_line
			(start -4.4958 -1.5748)
			(end 3.5814 -1.5748)
			(stroke
				(width 0.1524)
				(type default)
			)
			(layer "F.SilkS")
		)
		(fp_line
			(start -4.4958 -0.4318)
			(end -4.4958 -1.5748)
			(stroke
				(width 0.1524)
				(type default)
			)
			(layer "F.SilkS")
		)
		(fp_line
			(start -4.4958 -0.4318)
			(end -4.064 0)
			(stroke
				(width 0.1524)
				(type default)
			)
			(layer "F.SilkS")
		)
		(fp_line
			(start -4.4958 0.4318)
			(end -4.4958 -0.4318)
			(stroke
				(width 0.1524)
				(type default)
			)
			(layer "F.SilkS")
		)
		(fp_line
			(start -4.4958 0.4318)
			(end -4.4958 1.5748)
			(stroke
				(width 0.1524)
				(type default)
			)
			(layer "F.SilkS")
		)
		(fp_line
			(start -4.318 1.5748)
			(end -4.318 3.556)
			(stroke
				(width 0.508)
				(type default)
			)
			(layer "F.SilkS")
		)
		(fp_line
			(start -4.064 0)
			(end -4.4958 0.4318)
			(stroke
				(width 0.1524)
				(type default)
			)
			(layer "F.SilkS")
		)
		(fp_line
			(start 3.5814 -1.5748)
			(end 3.5814 1.5748)
			(stroke
				(width 0.1524)
				(type default)
			)
			(layer "F.SilkS")
		)
		(fp_line
			(start 3.5814 1.5748)
			(end -4.4958 1.5748)
			(stroke
				(width 0.1524)
				(type default)
			)
			(layer "F.SilkS")
		)
		(fp_line
			(start 3.5814 1.5748)
			(end 3.5814 -1.5748)
			(stroke
				(width 0.1524)
				(type default)
			)
			(layer "F.SilkS")
		)
		(fp_poly
			(pts
				(xy -3.683 -1.5748) (xy 3.5814 -1.5748) (xy 3.5814 1.5748) (xy -3.683 1.5748)
			)
			(stroke
				(width 0)
				(type default)
			)
			(fill yes)
			(layer "F.SilkS")
		)
		(fp_rect
			(start -4.572 3.81)
			(end 4.572 -3.81)
			(stroke
				(width 0)
				(type default)
			)
			(fill no)
			(layer "F.CrtYd")
		)
		(fp_poly
			(pts
				(xy -4.572 -3.81) (xy 4.572 -3.81) (xy 4.572 3.81) (xy -4.572 3.81)
			)
			(stroke
				(width 0)
				(type default)
			)
			(fill no)
			(layer "F.Fab")
		)
		(pad "1" smd rect
			(at -3.4925 2.6162)
			(size 0.3556 1.524)
			(layers "F.Cu" "F.Mask" "F.Paste")
			(net "Net_1512")
		)
		(pad "2" smd rect
			(at -2.8575 2.6162)
			(size 0.3556 1.524)
			(layers "F.Cu" "F.Mask" "F.Paste")
			(net "SAS_HDD_PWR0")
		)
		(pad "3" smd rect
			(at -2.2225 2.6162)
			(size 0.3556 1.524)
			(layers "F.Cu" "F.Mask" "F.Paste")
			(net "SAS_HDD_PWR1")
		)
		(pad "4" smd rect
			(at -1.5875 2.6162)
			(size 0.3556 1.524)
			(layers "F.Cu" "F.Mask" "F.Paste")
			(net "SAS_HDD_PWR2")
		)
		(pad "5" smd rect
			(at -0.9525 2.6162)
			(size 0.3556 1.524)
			(layers "F.Cu" "F.Mask" "F.Paste")
			(net "SAS_HDD_PWR3")
		)
		(pad "6" smd rect
			(at -0.3175 2.6162)
			(size 0.3556 1.524)
			(layers "F.Cu" "F.Mask" "F.Paste")
			(net "SAS_HDD_PWR4")
		)
		(pad "7" smd rect
			(at 0.3175 2.6162)
			(size 0.3556 1.524)
			(layers "F.Cu" "F.Mask" "F.Paste")
			(net "SAS_HDD_PWR5")
		)
		(pad "8" smd rect
			(at 0.9525 2.6162)
			(size 0.3556 1.524)
			(layers "F.Cu" "F.Mask" "F.Paste")
			(net "SAS_HDD_PWR6")
		)
		(pad "9" smd rect
			(at 1.5875 2.6162)
			(size 0.3556 1.524)
			(layers "F.Cu" "F.Mask" "F.Paste")
			(net "SAS_HDD_PWR7")
		)
		(pad "10" smd rect
			(at 2.2225 2.6162)
			(size 0.3556 1.524)
			(layers "F.Cu" "F.Mask" "F.Paste")
			(net "SAS_HDD_PWR8")
		)
		(pad "11" smd rect
			(at 2.8575 2.6162)
			(size 0.3556 1.524)
			(layers "F.Cu" "F.Mask" "F.Paste")
			(net "SAS_HDD_PWR9")
		)
		(pad "12" smd rect
			(at 3.4925 2.6162)
			(size 0.3556 1.524)
			(layers "F.Cu" "F.Mask" "F.Paste")
			(net "GND")
		)
		(pad "13" smd rect
			(at 3.4925 -2.6162)
			(size 0.3556 1.524)
			(layers "F.Cu" "F.Mask" "F.Paste")
			(net "SAS_HDD_PWR9_PCIE")
		)
		(pad "14" smd rect
			(at 2.8575 -2.6162)
			(size 0.3556 1.524)
			(layers "F.Cu" "F.Mask" "F.Paste")
			(net "SAS_HDD_PWR8_PCIE")
		)
		(pad "15" smd rect
			(at 2.2225 -2.6162)
			(size 0.3556 1.524)
			(layers "F.Cu" "F.Mask" "F.Paste")
			(net "SAS_HDD_PWR7_PCIE")
		)
		(pad "16" smd rect
			(at 1.5875 -2.6162)
			(size 0.3556 1.524)
			(layers "F.Cu" "F.Mask" "F.Paste")
			(net "SAS_HDD_PWR6_PCIE")
		)
		(pad "17" smd rect
			(at 0.9525 -2.6162)
			(size 0.3556 1.524)
			(layers "F.Cu" "F.Mask" "F.Paste")
			(net "SAS_HDD_PWR5_PCIE")
		)
		(pad "18" smd rect
			(at 0.3175 -2.6162)
			(size 0.3556 1.524)
			(layers "F.Cu" "F.Mask" "F.Paste")
			(net "SAS_HDD_PWR4_PCIE")
		)
		(pad "19" smd rect
			(at -0.3175 -2.6162)
			(size 0.3556 1.524)
			(layers "F.Cu" "F.Mask" "F.Paste")
			(net "SAS_HDD_PWR3_PCIE")
		)
		(pad "20" smd rect
			(at -0.9525 -2.6162)
			(size 0.3556 1.524)
			(layers "F.Cu" "F.Mask" "F.Paste")
			(net "SAS_HDD_PWR2_PCIE")
		)
		(pad "21" smd rect
			(at -1.5875 -2.6162)
			(size 0.3556 1.524)
			(layers "F.Cu" "F.Mask" "F.Paste")
			(net "SAS_HDD_PWR1_PCIE")
		)
		(pad "22" smd rect
			(at -2.2225 -2.6162)
			(size 0.3556 1.524)
			(layers "F.Cu" "F.Mask" "F.Paste")
			(net "SAS_HDD_PWR0_PCIE")
		)
		(pad "23" smd rect
			(at -2.8575 -2.6162)
			(size 0.3556 1.524)
			(layers "F.Cu" "F.Mask" "F.Paste")
			(net "PCIE_MATED#_AB")
		)
		(pad "24" smd rect
			(at -3.4925 -2.6162)
			(size 0.3556 1.524)
			(layers "F.Cu" "F.Mask" "F.Paste")
			(net "P3V3_STBY")
		)
	)
	(footprint ""
		(layer "F.Cu")
		(at 117.729 -35.941)
		(property "Reference" "STP133"
			(at 0 0 0)
			(layer "F.SilkS")
			(hide yes)
			(effects
				(font
					(size 1.27 1.27)
				)
			)
		)
		(property "Value" "TPAD28"
			(at 0.0127 -1.8034 0)
			(unlocked yes)
			(layer "F.Fab")
			(hide yes)
			(effects
				(font
					(size 1.016 1.016)
					(thickness 0.1524)
				)
			)
		)
		(property "Device Type" "TPAD28"
			(at 0.0127 -3.3274 0)
			(unlocked yes)
			(layer "F.Fab")
			(hide yes)
			(effects
				(font
					(size 1.016 1.016)
					(thickness 0.1524)
				)
			)
		)
		(duplicate_pad_numbers_are_jumpers no)
		(fp_poly
			(pts
				(arc
					(start 0.3556 0)
					(mid -0.3556 0)
					(end 0.3556 0)
				)
			)
			(stroke
				(width 0)
				(type default)
			)
			(fill no)
			(layer "F.CrtYd")
		)
		(fp_poly
			(pts
				(arc
					(start 0.6096 0)
					(mid -0.6096 0)
					(end 0.6096 0)
				)
			)
			(stroke
				(width 0)
				(type default)
			)
			(fill no)
			(layer "F.Fab")
		)
		(pad "1" smd circle
			(at 0 0)
			(size 0.7112 0.7112)
			(layers "F.Cu" "F.Mask" "F.Paste")
			(net "IOC_GPIO_8")
		)
	)
)
